(kicad_pcb
	(version 20260206)
	(generator "pcbnew")
	(generator_version "10.0")
	(general
		(thickness 1.6)
		(legacy_teardrops no)
	)
	(paper "A4")
	(title_block
		(title "04192023_DAF0TMB3IC0_F0TG_MB_C_brd_V02_OCP.brd")
		(comment 1 "Grand Teton / footprints 3722-3727 of 8354")
	)
	(layers
		(0 "F.Cu" signal "TOP")
		(4 "In1.Cu" signal "GND")
		(6 "In2.Cu" signal "IN1")
		(8 "In3.Cu" signal "GND1")
		(10 "In4.Cu" signal "IN2")
		(12 "In5.Cu" signal "GND2")
		(14 "In6.Cu" signal "IN3")
		(16 "In7.Cu" signal "GND3")
		(18 "In8.Cu" signal "VCC")
		(20 "In9.Cu" signal "VCC1")
		(22 "In10.Cu" signal "GND4")
		(24 "In11.Cu" signal "IN4")
		(26 "In12.Cu" signal "GND5")
		(28 "In13.Cu" signal "IN5")
		(30 "In14.Cu" signal "GND6")
		(32 "In15.Cu" signal "IN6")
		(34 "In16.Cu" signal "GND7")
		(2 "B.Cu" signal "BOTTOM")
		(9 "F.Adhes" user "F.Adhesive")
		(11 "B.Adhes" user "B.Adhesive")
		(13 "F.Paste" user "Package Geometry/Pastemask Top")
		(15 "B.Paste" user "Package Geometry/Pastemask Bottom")
		(5 "F.SilkS" user "Ref Des/Silkscreen Top")
		(7 "B.SilkS" user "Ref Des/Silkscreen Bottom")
		(1 "F.Mask" user "Board Geometry/Soldermask Top")
		(3 "B.Mask" user "Board Geometry/Soldermask Bottom")
		(17 "Dwgs.User" user "User.Drawings")
		(19 "Cmts.User" user "User.Comments")
		(21 "Eco1.User" user "User.Eco1")
		(23 "Eco2.User" user "User.Eco2")
		(25 "Edge.Cuts" user "Board Geometry/Outline")
		(27 "Margin" user)
		(31 "F.CrtYd" user "Package Geometry/Place Bound Top")
		(29 "B.CrtYd" user "Package Geometry/Place Bound Bottom")
		(35 "F.Fab" user "Ref Des/Assembly Top")
		(33 "B.Fab" user "Ref Des/Assembly Bottom")
	)
	(footprint ""
		(layer "F.Cu")
		(at 265.395964 -385.27736 90)
		(property "Reference" "PPQ7"
			(at -7.603236 -2.160524 0)
			(unlocked yes)
			(layer "F.SilkS")
			(effects
				(font
					(size 0.7874 0.5842)
					(thickness 0.1524)
				)
				(justify left)
			)
		)
		(property "Value" ""
			(at 0 0 90)
			(layer "F.Fab")
			(effects
				(font
					(size 1.27 1.27)
				)
			)
		)
		(duplicate_pad_numbers_are_jumpers no)
		(fp_line
			(start 2.350008 -2.649982)
			(end 2.350008 -2.4892)
			(stroke
				(width 0.1524)
				(type default)
			)
			(layer "F.SilkS")
		)
		(fp_line
			(start -2.350008 -2.649982)
			(end 2.350008 -2.649982)
			(stroke
				(width 0.1524)
				(type default)
			)
			(layer "F.SilkS")
		)
		(fp_line
			(start -2.350008 -2.4384)
			(end -2.350008 -2.649982)
			(stroke
				(width 0.1524)
				(type default)
			)
			(layer "F.SilkS")
		)
		(fp_line
			(start 2.350008 2.4892)
			(end 2.350008 2.649982)
			(stroke
				(width 0.1524)
				(type default)
			)
			(layer "F.SilkS")
		)
		(fp_line
			(start 2.350008 2.649982)
			(end -2.350008 2.649982)
			(stroke
				(width 0.1524)
				(type default)
			)
			(layer "F.SilkS")
		)
		(fp_line
			(start -2.350008 2.649982)
			(end -2.350008 2.413)
			(stroke
				(width 0.1524)
				(type default)
			)
			(layer "F.SilkS")
		)
		(fp_poly
			(pts
				(xy -3.447796 -3.466338) (xy -2.648712 -3.428238) (xy -3.116834 -2.40792)
			)
			(stroke
				(width 0)
				(type default)
			)
			(fill yes)
			(layer "F.SilkS")
		)
		(fp_line
			(start 2.350008 -2.649982)
			(end 2.350008 2.649982)
			(stroke
				(width 0.1)
				(type default)
			)
			(layer "F.Fab")
		)
		(fp_line
			(start -2.350008 -2.649982)
			(end 2.350008 -2.649982)
			(stroke
				(width 0.1)
				(type default)
			)
			(layer "F.Fab")
		)
		(fp_line
			(start 2.350008 2.649982)
			(end -2.350008 2.649982)
			(stroke
				(width 0.1)
				(type default)
			)
			(layer "F.Fab")
		)
		(fp_line
			(start -2.350008 2.649982)
			(end -2.350008 -2.649982)
			(stroke
				(width 0.1)
				(type default)
			)
			(layer "F.Fab")
		)
		(fp_poly
			(pts
				(xy -3.717544 -1.905) (xy -4.758944 -2.3241) (xy -4.758944 -1.524)
			)
			(stroke
				(width 0)
				(type default)
			)
			(fill yes)
			(layer "F.Fab")
		)
		(pad "1" smd rect
			(at -2.999994 -1.905)
			(size 0.7112 1.1684)
			(layers "F.Cu" "F.Mask" "F.Paste")
			(net "P12V_AUX")
		)
		(pad "2" smd rect
			(at -2.999994 -0.635)
			(size 0.7112 1.1684)
			(layers "F.Cu" "F.Mask" "F.Paste")
			(net "P12V_AUX")
		)
		(pad "3" smd rect
			(at -2.999994 0.635)
			(size 0.7112 1.1684)
			(layers "F.Cu" "F.Mask" "F.Paste")
			(net "P12V_AUX")
		)
		(pad "4" smd rect
			(at -2.999994 1.905)
			(size 0.7112 1.1684)
			(layers "F.Cu" "F.Mask" "F.Paste")
			(net "P12V_HSC_GATE_G3")
		)
		(pad "5" smd circle
			(at 0.925068 0)
			(size 0 0)
			(layers "F.Cu" "F.Mask" "F.Paste")
			(net "P12V_MAIN_R")
		)
		(zone
			(layer "F.Cu")
			(hatch none 0.5)
			(connect_pads
				(clearance 0)
			)
			(min_thickness 0.25)
			(keepout
				(tracks not_allowed)
				(vias allowed)
				(pads allowed)
				(copperpour not_allowed)
				(footprints allowed)
			)
			(placement
				(enabled no)
				(sheetname "")
			)
			(fill
				(thermal_gap 0.5)
				(thermal_bridge_width 0.5)
				(island_removal_mode 0)
			)
			(polygon
				(pts
					(xy 262.754364 -383.7178) (xy 268.037564 -383.7178) (xy 268.037564 -382.92786) (xy 262.754364 -382.92786)
				)
			)
		)
	)
	(footprint ""
		(layer "F.Cu")
		(at 112.267238 -41.17975 90)
		(property "Reference" "R6288"
			(at 0 0 90)
			(layer "F.SilkS")
			(hide yes)
			(effects
				(font
					(size 1.27 1.27)
				)
			)
		)
		(property "Value" ""
			(at 0 0 90)
			(layer "F.Fab")
			(effects
				(font
					(size 1.27 1.27)
				)
			)
		)
		(duplicate_pad_numbers_are_jumpers no)
		(fp_line
			(start 0.7874 -0.4064)
			(end 0.7874 0.4064)
			(stroke
				(width 0.1524)
				(type default)
			)
			(layer "F.SilkS")
		)
		(fp_line
			(start -0.7874 -0.4064)
			(end 0.7874 -0.4064)
			(stroke
				(width 0.1524)
				(type default)
			)
			(layer "F.SilkS")
		)
		(fp_line
			(start 0.7874 0.4064)
			(end -0.7874 0.4064)
			(stroke
				(width 0.1524)
				(type default)
			)
			(layer "F.SilkS")
		)
		(fp_line
			(start -0.7874 0.4064)
			(end -0.7874 -0.4064)
			(stroke
				(width 0.1524)
				(type default)
			)
			(layer "F.SilkS")
		)
		(fp_line
			(start -0.12065 -0.305054)
			(end -0.12065 -0.2794)
			(stroke
				(width 0.1)
				(type default)
			)
			(layer "F.Fab")
		)
		(fp_line
			(start -0.67945 -0.305054)
			(end -0.12065 -0.305054)
			(stroke
				(width 0.1)
				(type default)
			)
			(layer "F.Fab")
		)
		(fp_line
			(start 0.67945 -0.3048)
			(end 0.67945 0.3048)
			(stroke
				(width 0.1)
				(type default)
			)
			(layer "F.Fab")
		)
		(fp_line
			(start 0.12065 -0.3048)
			(end 0.67945 -0.3048)
			(stroke
				(width 0.1)
				(type default)
			)
			(layer "F.Fab")
		)
		(fp_line
			(start 0.12065 -0.2794)
			(end 0.12065 -0.3048)
			(stroke
				(width 0.1)
				(type default)
			)
			(layer "F.Fab")
		)
		(fp_line
			(start -0.12065 -0.2794)
			(end 0.12065 -0.2794)
			(stroke
				(width 0.1)
				(type default)
			)
			(layer "F.Fab")
		)
		(fp_line
			(start 0.120396 0.2794)
			(end -0.12065 0.2794)
			(stroke
				(width 0.1)
				(type default)
			)
			(layer "F.Fab")
		)
		(fp_line
			(start -0.12065 0.2794)
			(end -0.12065 0.3048)
			(stroke
				(width 0.1)
				(type default)
			)
			(layer "F.Fab")
		)
		(fp_line
			(start 0.67945 0.3048)
			(end 0.120396 0.3048)
			(stroke
				(width 0.1)
				(type default)
			)
			(layer "F.Fab")
		)
		(fp_line
			(start 0.120396 0.3048)
			(end 0.120396 0.2794)
			(stroke
				(width 0.1)
				(type default)
			)
			(layer "F.Fab")
		)
		(fp_line
			(start -0.12065 0.3048)
			(end -0.67945 0.3048)
			(stroke
				(width 0.1)
				(type default)
			)
			(layer "F.Fab")
		)
		(fp_line
			(start -0.67945 0.3048)
			(end -0.67945 -0.305054)
			(stroke
				(width 0.1)
				(type default)
			)
			(layer "F.Fab")
		)
		(pad "1" smd circle
			(at -0.40005 0 90)
			(size 0 0)
			(layers "F.Cu" "F.Mask" "F.Paste")
			(net "USB_HUB2_TI_PWRCTL_POL")
		)
		(pad "2" smd circle
			(at 0.40005 0 90)
			(size 0 0)
			(layers "F.Cu" "F.Mask" "F.Paste")
			(net "GND")
		)
	)
	(footprint ""
		(layer "F.Cu")
		(at 16.110966 -92.687648 90)
		(property "Reference" "R3658"
			(at 0 0 90)
			(layer "F.SilkS")
			(hide yes)
			(effects
				(font
					(size 1.27 1.27)
				)
			)
		)
		(property "Value" ""
			(at 0 0 90)
			(layer "F.Fab")
			(effects
				(font
					(size 1.27 1.27)
				)
			)
		)
		(duplicate_pad_numbers_are_jumpers no)
		(fp_line
			(start 0.7874 -0.4064)
			(end 0.7874 0.4064)
			(stroke
				(width 0.1524)
				(type default)
			)
			(layer "F.SilkS")
		)
		(fp_line
			(start -0.7874 -0.4064)
			(end 0.7874 -0.4064)
			(stroke
				(width 0.1524)
				(type default)
			)
			(layer "F.SilkS")
		)
		(fp_line
			(start 0.7874 0.4064)
			(end -0.7874 0.4064)
			(stroke
				(width 0.1524)
				(type default)
			)
			(layer "F.SilkS")
		)
		(fp_line
			(start -0.7874 0.4064)
			(end -0.7874 -0.4064)
			(stroke
				(width 0.1524)
				(type default)
			)
			(layer "F.SilkS")
		)
		(fp_line
			(start -0.12065 -0.305054)
			(end -0.12065 -0.2794)
			(stroke
				(width 0.1)
				(type default)
			)
			(layer "F.Fab")
		)
		(fp_line
			(start -0.67945 -0.305054)
			(end -0.12065 -0.305054)
			(stroke
				(width 0.1)
				(type default)
			)
			(layer "F.Fab")
		)
		(fp_line
			(start 0.67945 -0.3048)
			(end 0.67945 0.3048)
			(stroke
				(width 0.1)
				(type default)
			)
			(layer "F.Fab")
		)
		(fp_line
			(start 0.12065 -0.3048)
			(end 0.67945 -0.3048)
			(stroke
				(width 0.1)
				(type default)
			)
			(layer "F.Fab")
		)
		(fp_line
			(start 0.12065 -0.2794)
			(end 0.12065 -0.3048)
			(stroke
				(width 0.1)
				(type default)
			)
			(layer "F.Fab")
		)
		(fp_line
			(start -0.12065 -0.2794)
			(end 0.12065 -0.2794)
			(stroke
				(width 0.1)
				(type default)
			)
			(layer "F.Fab")
		)
		(fp_line
			(start 0.120396 0.2794)
			(end -0.12065 0.2794)
			(stroke
				(width 0.1)
				(type default)
			)
			(layer "F.Fab")
		)
		(fp_line
			(start -0.12065 0.2794)
			(end -0.12065 0.3048)
			(stroke
				(width 0.1)
				(type default)
			)
			(layer "F.Fab")
		)
		(fp_line
			(start 0.67945 0.3048)
			(end 0.120396 0.3048)
			(stroke
				(width 0.1)
				(type default)
			)
			(layer "F.Fab")
		)
		(fp_line
			(start 0.120396 0.3048)
			(end 0.120396 0.2794)
			(stroke
				(width 0.1)
				(type default)
			)
			(layer "F.Fab")
		)
		(fp_line
			(start -0.12065 0.3048)
			(end -0.67945 0.3048)
			(stroke
				(width 0.1)
				(type default)
			)
			(layer "F.Fab")
		)
		(fp_line
			(start -0.67945 0.3048)
			(end -0.67945 -0.305054)
			(stroke
				(width 0.1)
				(type default)
			)
			(layer "F.Fab")
		)
		(pad "1" smd circle
			(at -0.40005 0 90)
			(size 0 0)
			(layers "F.Cu" "F.Mask" "F.Paste")
			(net "P3V3_AUX")
		)
		(pad "2" smd circle
			(at 0.40005 0 90)
			(size 0 0)
			(layers "F.Cu" "F.Mask" "F.Paste")
			(net "USB_HUB_OVCUR3")
		)
	)
	(footprint ""
		(layer "F.Cu")
		(at 360.762042 -397.87576)
		(property "Reference" "R1398"
			(at 0 0 0)
			(layer "F.SilkS")
			(hide yes)
			(effects
				(font
					(size 1.27 1.27)
				)
			)
		)
		(property "Value" ""
			(at 0 0 0)
			(layer "F.Fab")
			(effects
				(font
					(size 1.27 1.27)
				)
			)
		)
		(duplicate_pad_numbers_are_jumpers no)
		(fp_line
			(start -0.32512 -0.175006)
			(end 0.32512 -0.175006)
			(stroke
				(width 0.1)
				(type default)
			)
			(layer "F.Fab")
		)
		(fp_line
			(start -0.32512 0.175006)
			(end -0.32512 -0.175006)
			(stroke
				(width 0.1)
				(type default)
			)
			(layer "F.Fab")
		)
		(fp_line
			(start 0.32512 -0.175006)
			(end 0.32512 0.175006)
			(stroke
				(width 0.1)
				(type default)
			)
			(layer "F.Fab")
		)
		(fp_line
			(start 0.32512 0.175006)
			(end -0.32512 0.175006)
			(stroke
				(width 0.1)
				(type default)
			)
			(layer "F.Fab")
		)
		(pad "1" smd rect
			(at -0.2667 0)
			(size 0.3048 0.381)
			(layers "F.Cu" "F.Mask" "F.Paste")
			(net "RXDET_BYP_RT_CPU0_P1")
		)
		(pad "2" smd rect
			(at 0.2667 0 180)
			(size 0.3048 0.381)
			(layers "F.Cu" "F.Mask" "F.Paste")
			(net "GND")
		)
	)
	(footprint ""
		(layer "F.Cu")
		(at 19.240754 -36.878514 180)
		(property "Reference" "R1328"
			(at 0 0 180)
			(layer "F.SilkS")
			(hide yes)
			(effects
				(font
					(size 1.27 1.27)
				)
			)
		)
		(property "Value" ""
			(at 0 0 180)
			(layer "F.Fab")
			(effects
				(font
					(size 1.27 1.27)
				)
			)
		)
		(duplicate_pad_numbers_are_jumpers no)
		(fp_line
			(start 0.7874 0.4064)
			(end -0.7874 0.4064)
			(stroke
				(width 0.1524)
				(type default)
			)
			(layer "F.SilkS")
		)
		(fp_line
			(start 0.7874 -0.4064)
			(end 0.7874 0.4064)
			(stroke
				(width 0.1524)
				(type default)
			)
			(layer "F.SilkS")
		)
		(fp_line
			(start -0.7874 0.4064)
			(end -0.7874 -0.4064)
			(stroke
				(width 0.1524)
				(type default)
			)
			(layer "F.SilkS")
		)
		(fp_line
			(start -0.7874 -0.4064)
			(end 0.7874 -0.4064)
			(stroke
				(width 0.1524)
				(type default)
			)
			(layer "F.SilkS")
		)
		(fp_line
			(start 0.67945 0.3048)
			(end 0.120396 0.3048)
			(stroke
				(width 0.1)
				(type default)
			)
			(layer "F.Fab")
		)
		(fp_line
			(start 0.67945 -0.3048)
			(end 0.67945 0.3048)
			(stroke
				(width 0.1)
				(type default)
			)
			(layer "F.Fab")
		)
		(fp_line
			(start 0.12065 -0.2794)
			(end 0.12065 -0.3048)
			(stroke
				(width 0.1)
				(type default)
			)
			(layer "F.Fab")
		)
		(fp_line
			(start 0.12065 -0.3048)
			(end 0.67945 -0.3048)
			(stroke
				(width 0.1)
				(type default)
			)
			(layer "F.Fab")
		)
		(fp_line
			(start 0.120396 0.3048)
			(end 0.120396 0.2794)
			(stroke
				(width 0.1)
				(type default)
			)
			(layer "F.Fab")
		)
		(fp_line
			(start 0.120396 0.2794)
			(end -0.12065 0.2794)
			(stroke
				(width 0.1)
				(type default)
			)
			(layer "F.Fab")
		)
		(fp_line
			(start -0.12065 0.3048)
			(end -0.67945 0.3048)
			(stroke
				(width 0.1)
				(type default)
			)
			(layer "F.Fab")
		)
		(fp_line
			(start -0.12065 0.2794)
			(end -0.12065 0.3048)
			(stroke
				(width 0.1)
				(type default)
			)
			(layer "F.Fab")
		)
		(fp_line
			(start -0.12065 -0.2794)
			(end 0.12065 -0.2794)
			(stroke
				(width 0.1)
				(type default)
			)
			(layer "F.Fab")
		)
		(fp_line
			(start -0.12065 -0.305054)
			(end -0.12065 -0.2794)
			(stroke
				(width 0.1)
				(type default)
			)
			(layer "F.Fab")
		)
		(fp_line
			(start -0.67945 0.3048)
			(end -0.67945 -0.305054)
			(stroke
				(width 0.1)
				(type default)
			)
			(layer "F.Fab")
		)
		(fp_line
			(start -0.67945 -0.305054)
			(end -0.12065 -0.305054)
			(stroke
				(width 0.1)
				(type default)
			)
			(layer "F.Fab")
		)
		(pad "1" smd circle
			(at -0.40005 0 180)
			(size 0 0)
			(layers "F.Cu" "F.Mask" "F.Paste")
			(net "P3V3_AUX")
		)
		(pad "2" smd circle
			(at 0.40005 0 180)
			(size 0 0)
			(layers "F.Cu" "F.Mask" "F.Paste")
			(net "OCP_V3_2_P3V3_P12V_ADC_R_ALERT")
		)
	)
	(footprint ""
		(layer "F.Cu")
		(at 148.494242 -108.699046 180)
		(property "Reference" "R333"
			(at 0 0 180)
			(layer "F.SilkS")
			(hide yes)
			(effects
				(font
					(size 1.27 1.27)
				)
			)
		)
		(property "Value" ""
			(at 0 0 180)
			(layer "F.Fab")
			(effects
				(font
					(size 1.27 1.27)
				)
			)
		)
		(duplicate_pad_numbers_are_jumpers no)
		(fp_line
			(start 0.7874 0.4064)
			(end -0.7874 0.4064)
			(stroke
				(width 0.1524)
				(type default)
			)
			(layer "F.SilkS")
		)
		(fp_line
			(start 0.7874 -0.4064)
			(end 0.7874 0.4064)
			(stroke
				(width 0.1524)
				(type default)
			)
			(layer "F.SilkS")
		)
		(fp_line
			(start -0.7874 0.4064)
			(end -0.7874 -0.4064)
			(stroke
				(width 0.1524)
				(type default)
			)
			(layer "F.SilkS")
		)
		(fp_line
			(start -0.7874 -0.4064)
			(end 0.7874 -0.4064)
			(stroke
				(width 0.1524)
				(type default)
			)
			(layer "F.SilkS")
		)
		(fp_line
			(start 0.67945 0.3048)
			(end 0.120396 0.3048)
			(stroke
				(width 0.1)
				(type default)
			)
			(layer "F.Fab")
		)
		(fp_line
			(start 0.67945 -0.3048)
			(end 0.67945 0.3048)
			(stroke
				(width 0.1)
				(type default)
			)
			(layer "F.Fab")
		)
		(fp_line
			(start 0.12065 -0.2794)
			(end 0.12065 -0.3048)
			(stroke
				(width 0.1)
				(type default)
			)
			(layer "F.Fab")
		)
		(fp_line
			(start 0.12065 -0.3048)
			(end 0.67945 -0.3048)
			(stroke
				(width 0.1)
				(type default)
			)
			(layer "F.Fab")
		)
		(fp_line
			(start 0.120396 0.3048)
			(end 0.120396 0.2794)
			(stroke
				(width 0.1)
				(type default)
			)
			(layer "F.Fab")
		)
		(fp_line
			(start 0.120396 0.2794)
			(end -0.12065 0.2794)
			(stroke
				(width 0.1)
				(type default)
			)
			(layer "F.Fab")
		)
		(fp_line
			(start -0.12065 0.3048)
			(end -0.67945 0.3048)
			(stroke
				(width 0.1)
				(type default)
			)
			(layer "F.Fab")
		)
		(fp_line
			(start -0.12065 0.2794)
			(end -0.12065 0.3048)
			(stroke
				(width 0.1)
				(type default)
			)
			(layer "F.Fab")
		)
		(fp_line
			(start -0.12065 -0.2794)
			(end 0.12065 -0.2794)
			(stroke
				(width 0.1)
				(type default)
			)
			(layer "F.Fab")
		)
		(fp_line
			(start -0.12065 -0.305054)
			(end -0.12065 -0.2794)
			(stroke
				(width 0.1)
				(type default)
			)
			(layer "F.Fab")
		)
		(fp_line
			(start -0.67945 0.3048)
			(end -0.67945 -0.305054)
			(stroke
				(width 0.1)
				(type default)
			)
			(layer "F.Fab")
		)
		(fp_line
			(start -0.67945 -0.305054)
			(end -0.12065 -0.305054)
			(stroke
				(width 0.1)
				(type default)
			)
			(layer "F.Fab")
		)
		(pad "1" smd circle
			(at -0.40005 0 180)
			(size 0 0)
			(layers "F.Cu" "F.Mask" "F.Paste")
			(net "FM_P5V_EN")
		)
		(pad "2" smd circle
			(at 0.40005 0 180)
			(size 0 0)
			(layers "F.Cu" "F.Mask" "F.Paste")
			(net "VR_P5V_EN")
		)
	)
)
